# S9S_MB_2U (Grand Teton) — schematic netlist excerpt (pin names and nets, part order shuffled) for the footprints in the layout excerpt that follows; sources: Cadence DE-HDL packaged netlist, KiCad conversion of 03242023_DA0F0TMBIJ0_F0T_Motherboard_J_brd_V01_OCP.brd

PR447  Q_RES  0 5% CHIP  pkg 0402LF  page 271 : A = P5V ; B = PVCCFA_EHV_FIVRA_CPU0_PVCC2
R3870  Q_RES  0 5% EMPTY  pkg 0402LF  page 156 : A = P12V_OCP_SENSE_1 ; B = P12V_OCP_SFF_ISENSE_MAM_TIC

(kicad_pcb
	(version 20260206)
	(generator "pcbnew")
	(generator_version "10.0")
	(general
		(thickness 1.6)
		(legacy_teardrops no)
	)
	(paper "A4")
	(title_block
		(title "03242023_DA0F0TMBIJ0_F0T_Motherboard_J_brd_V01_OCP.brd")
		(comment 1 "Grand Teton / footprints 619-620 of 6105")
	)
	(layers
		(0 "F.Cu" signal "TOP")
		(4 "In1.Cu" signal "GND")
		(6 "In2.Cu" signal "IN1")
		(8 "In3.Cu" signal "GND1")
		(10 "In4.Cu" signal "IN2")
		(12 "In5.Cu" signal "GND2")
		(14 "In6.Cu" signal "IN3")
		(16 "In7.Cu" signal "GND3")
		(18 "In8.Cu" signal "VCC")
		(20 "In9.Cu" signal "VCC1")
		(22 "In10.Cu" signal "GND4")
		(24 "In11.Cu" signal "IN4")
		(26 "In12.Cu" signal "GND5")
		(28 "In13.Cu" signal "IN5")
		(30 "In14.Cu" signal "GND6")
		(32 "In15.Cu" signal "IN6")
		(34 "In16.Cu" signal "GND7")
		(2 "B.Cu" signal "BOTTOM")
		(9 "F.Adhes" user "F.Adhesive")
		(11 "B.Adhes" user "B.Adhesive")
		(13 "F.Paste" user "Package Geometry/Pastemask Top")
		(15 "B.Paste" user "Package Geometry/Pastemask Bottom")
		(5 "F.SilkS" user "Ref Des/Silkscreen Top")
		(7 "B.SilkS" user "Ref Des/Silkscreen Bottom")
		(1 "F.Mask" user "Board Geometry/Soldermask Top")
		(3 "B.Mask" user "Board Geometry/Soldermask Bottom")
		(17 "Dwgs.User" user "User.Drawings")
		(19 "Cmts.User" user "User.Comments")
		(21 "Eco1.User" user "User.Eco1")
		(23 "Eco2.User" user "User.Eco2")
		(25 "Edge.Cuts" user "Board Geometry/Outline")
		(27 "Margin" user)
		(31 "F.CrtYd" user "Package Geometry/Place Bound Top")
		(29 "B.CrtYd" user "Package Geometry/Place Bound Bottom")
		(35 "F.Fab" user "Ref Des/Assembly Top")
		(33 "B.Fab" user "Ref Des/Assembly Bottom")
	)
	(footprint ""
		(layer "F.Cu")
		(at 434.808122 -32.573468 180)
		(property "Reference" "R3870"
			(at 0 0 180)
			(layer "F.SilkS")
			(hide yes)
			(effects
				(font
					(size 1.27 1.27)
				)
			)
		)
		(property "Value" ""
			(at 0 0 180)
			(layer "F.Fab")
			(effects
				(font
					(size 1.27 1.27)
				)
			)
		)
		(duplicate_pad_numbers_are_jumpers no)
		(fp_line
			(start 0.7874 0.4064)
			(end -0.7874 0.4064)
			(stroke
				(width 0.1524)
				(type default)
			)
			(layer "F.SilkS")
		)
		(fp_line
			(start 0.7874 -0.4064)
			(end 0.7874 0.4064)
			(stroke
				(width 0.1524)
				(type default)
			)
			(layer "F.SilkS")
		)
		(fp_line
			(start -0.7874 0.4064)
			(end -0.7874 -0.4064)
			(stroke
				(width 0.1524)
				(type default)
			)
			(layer "F.SilkS")
		)
		(fp_line
			(start -0.7874 -0.4064)
			(end 0.7874 -0.4064)
			(stroke
				(width 0.1524)
				(type default)
			)
			(layer "F.SilkS")
		)
		(fp_line
			(start 0.67945 0.3048)
			(end 0.120396 0.3048)
			(stroke
				(width 0.1)
				(type default)
			)
			(layer "F.Fab")
		)
		(fp_line
			(start 0.67945 -0.3048)
			(end 0.67945 0.3048)
			(stroke
				(width 0.1)
				(type default)
			)
			(layer "F.Fab")
		)
		(fp_line
			(start 0.12065 -0.2794)
			(end 0.12065 -0.3048)
			(stroke
				(width 0.1)
				(type default)
			)
			(layer "F.Fab")
		)
		(fp_line
			(start 0.12065 -0.3048)
			(end 0.67945 -0.3048)
			(stroke
				(width 0.1)
				(type default)
			)
			(layer "F.Fab")
		)
		(fp_line
			(start 0.120396 0.3048)
			(end 0.120396 0.2794)
			(stroke
				(width 0.1)
				(type default)
			)
			(layer "F.Fab")
		)
		(fp_line
			(start 0.120396 0.2794)
			(end -0.12065 0.2794)
			(stroke
				(width 0.1)
				(type default)
			)
			(layer "F.Fab")
		)
		(fp_line
			(start -0.12065 0.3048)
			(end -0.67945 0.3048)
			(stroke
				(width 0.1)
				(type default)
			)
			(layer "F.Fab")
		)
		(fp_line
			(start -0.12065 0.2794)
			(end -0.12065 0.3048)
			(stroke
				(width 0.1)
				(type default)
			)
			(layer "F.Fab")
		)
		(fp_line
			(start -0.12065 -0.2794)
			(end 0.12065 -0.2794)
			(stroke
				(width 0.1)
				(type default)
			)
			(layer "F.Fab")
		)
		(fp_line
			(start -0.12065 -0.305054)
			(end -0.12065 -0.2794)
			(stroke
				(width 0.1)
				(type default)
			)
			(layer "F.Fab")
		)
		(fp_line
			(start -0.67945 0.3048)
			(end -0.67945 -0.305054)
			(stroke
				(width 0.1)
				(type default)
			)
			(layer "F.Fab")
		)
		(fp_line
			(start -0.67945 -0.305054)
			(end -0.12065 -0.305054)
			(stroke
				(width 0.1)
				(type default)
			)
			(layer "F.Fab")
		)
		(pad "1" smd rect
			(at -0.40005 0)
			(size 0.4572 0.508)
			(layers "F.Cu" "F.Mask" "F.Paste")
			(net "P12V_OCP_SENSE_1")
		)
		(pad "2" smd rect
			(at 0.40005 0)
			(size 0.4572 0.508)
			(layers "F.Cu" "F.Mask" "F.Paste")
			(net "P12V_OCP_SFF_ISENSE_MAM_TIC")
		)
	)
	(footprint ""
		(layer "F.Cu")
		(at 283.826712 -363.881416)
		(property "Reference" "PR447"
			(at 0 0 0)
			(layer "F.SilkS")
			(hide yes)
			(effects
				(font
					(size 1.27 1.27)
				)
			)
		)
		(property "Value" ""
			(at 0 0 0)
			(layer "F.Fab")
			(effects
				(font
					(size 1.27 1.27)
				)
			)
		)
		(duplicate_pad_numbers_are_jumpers no)
		(fp_line
			(start -0.7874 -0.4064)
			(end 0.7874 -0.4064)
			(stroke
				(width 0.1524)
				(type default)
			)
			(layer "F.SilkS")
		)
		(fp_line
			(start -0.7874 0.4064)
			(end -0.7874 -0.4064)
			(stroke
				(width 0.1524)
				(type default)
			)
			(layer "F.SilkS")
		)
		(fp_line
			(start 0.7874 -0.4064)
			(end 0.7874 0.4064)
			(stroke
				(width 0.1524)
				(type default)
			)
			(layer "F.SilkS")
		)
		(fp_line
			(start 0.7874 0.4064)
			(end -0.7874 0.4064)
			(stroke
				(width 0.1524)
				(type default)
			)
			(layer "F.SilkS")
		)
		(fp_line
			(start -0.67945 -0.305054)
			(end -0.12065 -0.305054)
			(stroke
				(width 0.1)
				(type default)
			)
			(layer "F.Fab")
		)
		(fp_line
			(start -0.67945 0.3048)
			(end -0.67945 -0.305054)
			(stroke
				(width 0.1)
				(type default)
			)
			(layer "F.Fab")
		)
		(fp_line
			(start -0.12065 -0.305054)
			(end -0.12065 -0.2794)
			(stroke
				(width 0.1)
				(type default)
			)
			(layer "F.Fab")
		)
		(fp_line
			(start -0.12065 -0.2794)
			(end 0.12065 -0.2794)
			(stroke
				(width 0.1)
				(type default)
			)
			(layer "F.Fab")
		)
		(fp_line
			(start -0.12065 0.2794)
			(end -0.12065 0.3048)
			(stroke
				(width 0.1)
				(type default)
			)
			(layer "F.Fab")
		)
		(fp_line
			(start -0.12065 0.3048)
			(end -0.67945 0.3048)
			(stroke
				(width 0.1)
				(type default)
			)
			(layer "F.Fab")
		)
		(fp_line
			(start 0.120396 0.2794)
			(end -0.12065 0.2794)
			(stroke
				(width 0.1)
				(type default)
			)
			(layer "F.Fab")
		)
		(fp_line
			(start 0.120396 0.3048)
			(end 0.120396 0.2794)
			(stroke
				(width 0.1)
				(type default)
			)
			(layer "F.Fab")
		)
		(fp_line
			(start 0.12065 -0.3048)
			(end 0.67945 -0.3048)
			(stroke
				(width 0.1)
				(type default)
			)
			(layer "F.Fab")
		)
		(fp_line
			(start 0.12065 -0.2794)
			(end 0.12065 -0.3048)
			(stroke
				(width 0.1)
				(type default)
			)
			(layer "F.Fab")
		)
		(fp_line
			(start 0.67945 -0.3048)
			(end 0.67945 0.3048)
			(stroke
				(width 0.1)
				(type default)
			)
			(layer "F.Fab")
		)
		(fp_line
			(start 0.67945 0.3048)
			(end 0.120396 0.3048)
			(stroke
				(width 0.1)
				(type default)
			)
			(layer "F.Fab")
		)
		(pad "1" smd circle
			(at -0.40005 0)
			(size 0 0)
			(layers "F.Cu" "F.Mask" "F.Paste")
			(net "P5V")
		)
		(pad "2" smd circle
			(at 0.40005 0)
			(size 0 0)
			(layers "F.Cu" "F.Mask" "F.Paste")
			(net "PVCCFA_EHV_FIVRA_CPU0_PVCC2")
		)
	)
)
